FILE_TYPE = CONNECTIVITY;
{Allegro Design Entry HDL 16.6-p007 (v16-6-112F) 10/10/2012}
"PAGE_NUMBER" = 110;
0"NC";
1"GND\g";
2"GND\g";
3"GND\g";
4"GND\g";
5"RCC_DFX_1940_4";
6"RCC_DFX_1940_3";
7"RCC_DFX_1940_1";
8"RCC_DFX_1940_2";
%"RCC_DFX1940"
"1","(-425,1350)","0","mstr_misc","I1";
;
$SEC"1"
CDS_SEC"1"
CDS_LIB"mstr_misc"
PART_NUMBER"N_A"
CDS_LOCATION"TC9F1"
MATERIAL"EMPTY"
PACK_TYPE"ID4"
LOCATION"TC9F1";
"GND"
$PN"1"2;
"IO1 \B"
$PN"2"6;
"IO2 \B"
$PN"3"6;
%"GND"
"1","(-2350,750)","0","mstr_symbols","I10";
;
SIZE"1B"
HDL_POWER"GND"
BODY_TYPE"PLUMBING"
CDS_LIB"mstr_symbols"
VOLTAGE"0.0V";
"A\NAC"1;
%"SNLABEL_A"
"1","(-1525,4450)","0","mstr_misc","I11";
;
CDS_LIB"mstr_misc"
BOM_COST"TEST_MFG"
PACK_TYPE"LABEL"
PART_NUMBER"N_A"
ROOM"LABELS"
CDS_LOCATION"LB2F1"
MATERIAL"EMPTY"
LOCATION"LB2F1";
%"SNLABEL_A"
"1","(-1525,3800)","0","mstr_misc","I12";
;
CDS_LIB"mstr_misc"
ROOM"LABELS"
CDS_LOCATION"LB5F1"
BOM_COST"TEST_MFG"
PACK_TYPE"LABEL"
PART_NUMBER"N_A"
MATERIAL"EMPTY"
LOCATION"LB5F1";
%"SNLABEL_A"
"1","(-1525,3125)","0","mstr_misc","I13";
;
CDS_LIB"mstr_misc"
BOM_COST"TEST_MFG"
PACK_TYPE"LABEL"
PART_NUMBER"N_A"
ROOM"LABELS"
CDS_LOCATION"LB2B1"
MATERIAL"EMPTY"
LOCATION"LB2B1";
%"SNLABEL_A"
"1","(-1500,2425)","0","mstr_misc","I14";
;
BOM_COST"TEST_MFG"
PACK_TYPE"LABEL"
PART_NUMBER"N_A"
ROOM"LABELS"
CDS_LOCATION"LB5B1"
CDS_LIB"mstr_misc"
MATERIAL"EMPTY"
LOCATION"LB5B1";
%"SNLABEL_A"
"1","(-1525,1900)","0","mstr_misc","I15";
;
BOM_COST"TEST_MFG"
PACK_TYPE"LABEL"
PART_NUMBER"N_A"
ROOM"LABELS"
CDS_LIB"mstr_misc"
CDS_LOCATION"LB6T1"
MATERIAL"EMPTY"
LOCATION"LB6T1";
%"GND"
"1","(-675,1150)","0","mstr_symbols","I2";
;
HDL_POWER"GND"
BODY_TYPE"PLUMBING"
CDS_LIB"mstr_symbols"
SIZE"1B"
VOLTAGE"0.0V";
"A\NAC"2;
%"RCC_DFX1940"
"1","(-400,925)","0","mstr_misc","I3";
;
$SEC"1"
CDS_SEC"1"
CDS_LOCATION"TC1G1"
PART_NUMBER"N_A"
CDS_LIB"mstr_misc"
MATERIAL"EMPTY"
LOCATION"TC1G1"
PACK_TYPE"ID4";
"GND"
$PN"1"3;
"IO1 \B"
$PN"2"5;
"IO2 \B"
$PN"3"5;
%"GND"
"1","(-675,750)","0","mstr_symbols","I4";
;
HDL_POWER"GND"
CDS_LIB"mstr_symbols"
BODY_TYPE"PLUMBING"
SIZE"1B"
VOLTAGE"0.0V";
"A\NAC"3;
%"RCC_DFX1940"
"1","(-2075,1325)","0","mstr_misc","I7";
;
$SEC"1"
CDS_SEC"1"
PART_NUMBER"N_A"
CDS_LIB"mstr_misc"
CDS_LOCATION"TC1A1"
MATERIAL"EMPTY"
PACK_TYPE"ID4"
LOCATION"TC1A1";
"GND"
$PN"1"4;
"IO1 \B"
$PN"2"7;
"IO2 \B"
$PN"3"7;
%"GND"
"1","(-2350,1125)","0","mstr_symbols","I8";
;
SIZE"1B"
HDL_POWER"GND"
BODY_TYPE"PLUMBING"
CDS_LIB"mstr_symbols"
VOLTAGE"0.0V";
"A\NAC"4;
%"RCC_DFX1940"
"1","(-2050,925)","0","mstr_misc","I9";
;
$SEC"1"
CDS_SEC"1"
PART_NUMBER"N_A"
CDS_LOCATION"TC9A1"
CDS_LIB"mstr_misc"
MATERIAL"EMPTY"
LOCATION"TC9A1"
PACK_TYPE"ID4";
"GND"
$PN"1"1;
"IO1 \B"
$PN"2"8;
"IO2 \B"
$PN"3"8;
END.
